(kicad_pcb
	(version 20260206)
	(generator "pcbnew")
	(generator_version "10.0")
	(general
		(thickness 1.6)
		(legacy_teardrops no)
	)
	(paper "A4")
	(title_block
		(title "04192023_DAF0TMB3IC0_F0TG_MB_C_brd_V02_OCP.brd")
		(comment 1 "Grand Teton / footprints 7697-7702 of 8354")
	)
	(layers
		(0 "F.Cu" signal "TOP")
		(4 "In1.Cu" signal "GND")
		(6 "In2.Cu" signal "IN1")
		(8 "In3.Cu" signal "GND1")
		(10 "In4.Cu" signal "IN2")
		(12 "In5.Cu" signal "GND2")
		(14 "In6.Cu" signal "IN3")
		(16 "In7.Cu" signal "GND3")
		(18 "In8.Cu" signal "VCC")
		(20 "In9.Cu" signal "VCC1")
		(22 "In10.Cu" signal "GND4")
		(24 "In11.Cu" signal "IN4")
		(26 "In12.Cu" signal "GND5")
		(28 "In13.Cu" signal "IN5")
		(30 "In14.Cu" signal "GND6")
		(32 "In15.Cu" signal "IN6")
		(34 "In16.Cu" signal "GND7")
		(2 "B.Cu" signal "BOTTOM")
		(9 "F.Adhes" user "F.Adhesive")
		(11 "B.Adhes" user "B.Adhesive")
		(13 "F.Paste" user "Package Geometry/Pastemask Top")
		(15 "B.Paste" user "Package Geometry/Pastemask Bottom")
		(5 "F.SilkS" user "Ref Des/Silkscreen Top")
		(7 "B.SilkS" user "Ref Des/Silkscreen Bottom")
		(1 "F.Mask" user "Board Geometry/Soldermask Top")
		(3 "B.Mask" user "Board Geometry/Soldermask Bottom")
		(17 "Dwgs.User" user "User.Drawings")
		(19 "Cmts.User" user "User.Comments")
		(21 "Eco1.User" user "User.Eco1")
		(23 "Eco2.User" user "User.Eco2")
		(25 "Edge.Cuts" user "Board Geometry/Outline")
		(27 "Margin" user)
		(31 "F.CrtYd" user "Package Geometry/Place Bound Top")
		(29 "B.CrtYd" user "Package Geometry/Place Bound Bottom")
		(35 "F.Fab" user "Ref Des/Assembly Top")
		(33 "B.Fab" user "Ref Des/Assembly Bottom")
	)
	(footprint ""
		(layer "B.Cu")
		(at 353.918774 -398.942052 90)
		(property "Reference" "C661"
			(at 0 0 90)
			(layer "B.SilkS")
			(hide yes)
			(effects
				(font
					(size 1.27 1.27)
				)
				(justify mirror)
			)
		)
		(property "Value" ""
			(at 0 0 90)
			(layer "B.Fab")
			(effects
				(font
					(size 1.27 1.27)
				)
				(justify mirror)
			)
		)
		(duplicate_pad_numbers_are_jumpers no)
		(fp_line
			(start 0.7874 -0.4064)
			(end -0.7874 -0.4064)
			(stroke
				(width 0.1524)
				(type default)
			)
			(layer "B.SilkS")
		)
		(fp_line
			(start -0.7874 -0.4064)
			(end -0.7874 0.4064)
			(stroke
				(width 0.1524)
				(type default)
			)
			(layer "B.SilkS")
		)
		(fp_line
			(start 0.7874 0.4064)
			(end 0.7874 -0.4064)
			(stroke
				(width 0.1524)
				(type default)
			)
			(layer "B.SilkS")
		)
		(fp_line
			(start -0.7874 0.4064)
			(end 0.7874 0.4064)
			(stroke
				(width 0.1524)
				(type default)
			)
			(layer "B.SilkS")
		)
		(fp_line
			(start 0.67945 -0.305054)
			(end 0.12065 -0.305054)
			(stroke
				(width 0.1)
				(type default)
			)
			(layer "B.Fab")
		)
		(fp_line
			(start 0.12065 -0.305054)
			(end 0.12065 -0.2794)
			(stroke
				(width 0.1)
				(type default)
			)
			(layer "B.Fab")
		)
		(fp_line
			(start -0.12065 -0.3048)
			(end -0.67945 -0.3048)
			(stroke
				(width 0.1)
				(type default)
			)
			(layer "B.Fab")
		)
		(fp_line
			(start -0.67945 -0.3048)
			(end -0.67945 0.3048)
			(stroke
				(width 0.1)
				(type default)
			)
			(layer "B.Fab")
		)
		(fp_line
			(start 0.12065 -0.2794)
			(end -0.12065 -0.2794)
			(stroke
				(width 0.1)
				(type default)
			)
			(layer "B.Fab")
		)
		(fp_line
			(start -0.12065 -0.2794)
			(end -0.12065 -0.3048)
			(stroke
				(width 0.1)
				(type default)
			)
			(layer "B.Fab")
		)
		(fp_line
			(start 0.12065 0.2794)
			(end 0.12065 0.3048)
			(stroke
				(width 0.1)
				(type default)
			)
			(layer "B.Fab")
		)
		(fp_line
			(start -0.120396 0.2794)
			(end 0.12065 0.2794)
			(stroke
				(width 0.1)
				(type default)
			)
			(layer "B.Fab")
		)
		(fp_line
			(start 0.67945 0.3048)
			(end 0.67945 -0.305054)
			(stroke
				(width 0.1)
				(type default)
			)
			(layer "B.Fab")
		)
		(fp_line
			(start 0.12065 0.3048)
			(end 0.67945 0.3048)
			(stroke
				(width 0.1)
				(type default)
			)
			(layer "B.Fab")
		)
		(fp_line
			(start -0.120396 0.3048)
			(end -0.120396 0.2794)
			(stroke
				(width 0.1)
				(type default)
			)
			(layer "B.Fab")
		)
		(fp_line
			(start -0.67945 0.3048)
			(end -0.120396 0.3048)
			(stroke
				(width 0.1)
				(type default)
			)
			(layer "B.Fab")
		)
		(pad "1" smd circle
			(at 0.40005 0 270)
			(size 0 0)
			(layers "B.Cu" "B.Mask" "B.Paste")
			(net "P0V9_CPU0_RT1_2A")
		)
		(pad "2" smd circle
			(at -0.40005 0 270)
			(size 0 0)
			(layers "B.Cu" "B.Mask" "B.Paste")
			(net "GND")
		)
	)
	(footprint ""
		(layer "B.Cu")
		(at 15.094458 -420.214298)
		(property "Reference" "C6009"
			(at 0 0 0)
			(layer "B.SilkS")
			(hide yes)
			(effects
				(font
					(size 1.27 1.27)
				)
				(justify mirror)
			)
		)
		(property "Value" ""
			(at 0 0 0)
			(layer "B.Fab")
			(effects
				(font
					(size 1.27 1.27)
				)
				(justify mirror)
			)
		)
		(duplicate_pad_numbers_are_jumpers no)
		(fp_line
			(start -0.7874 -0.4064)
			(end -0.7874 0.4064)
			(stroke
				(width 0.1524)
				(type default)
			)
			(layer "B.SilkS")
		)
		(fp_line
			(start -0.7874 0.4064)
			(end 0.7874 0.4064)
			(stroke
				(width 0.1524)
				(type default)
			)
			(layer "B.SilkS")
		)
		(fp_line
			(start 0.7874 -0.4064)
			(end -0.7874 -0.4064)
			(stroke
				(width 0.1524)
				(type default)
			)
			(layer "B.SilkS")
		)
		(fp_line
			(start 0.7874 0.4064)
			(end 0.7874 -0.4064)
			(stroke
				(width 0.1524)
				(type default)
			)
			(layer "B.SilkS")
		)
		(fp_line
			(start -0.67945 -0.3048)
			(end -0.67945 0.3048)
			(stroke
				(width 0.1)
				(type default)
			)
			(layer "B.Fab")
		)
		(fp_line
			(start -0.67945 0.3048)
			(end -0.120396 0.3048)
			(stroke
				(width 0.1)
				(type default)
			)
			(layer "B.Fab")
		)
		(fp_line
			(start -0.12065 -0.3048)
			(end -0.67945 -0.3048)
			(stroke
				(width 0.1)
				(type default)
			)
			(layer "B.Fab")
		)
		(fp_line
			(start -0.12065 -0.2794)
			(end -0.12065 -0.3048)
			(stroke
				(width 0.1)
				(type default)
			)
			(layer "B.Fab")
		)
		(fp_line
			(start -0.120396 0.2794)
			(end 0.12065 0.2794)
			(stroke
				(width 0.1)
				(type default)
			)
			(layer "B.Fab")
		)
		(fp_line
			(start -0.120396 0.3048)
			(end -0.120396 0.2794)
			(stroke
				(width 0.1)
				(type default)
			)
			(layer "B.Fab")
		)
		(fp_line
			(start 0.12065 -0.305054)
			(end 0.12065 -0.2794)
			(stroke
				(width 0.1)
				(type default)
			)
			(layer "B.Fab")
		)
		(fp_line
			(start 0.12065 -0.2794)
			(end -0.12065 -0.2794)
			(stroke
				(width 0.1)
				(type default)
			)
			(layer "B.Fab")
		)
		(fp_line
			(start 0.12065 0.2794)
			(end 0.12065 0.3048)
			(stroke
				(width 0.1)
				(type default)
			)
			(layer "B.Fab")
		)
		(fp_line
			(start 0.12065 0.3048)
			(end 0.67945 0.3048)
			(stroke
				(width 0.1)
				(type default)
			)
			(layer "B.Fab")
		)
		(fp_line
			(start 0.67945 -0.305054)
			(end 0.12065 -0.305054)
			(stroke
				(width 0.1)
				(type default)
			)
			(layer "B.Fab")
		)
		(fp_line
			(start 0.67945 0.3048)
			(end 0.67945 -0.305054)
			(stroke
				(width 0.1)
				(type default)
			)
			(layer "B.Fab")
		)
		(pad "1" smd circle
			(at 0.40005 0 180)
			(size 0 0)
			(layers "B.Cu" "B.Mask" "B.Paste")
			(net "P3V3_AUX")
		)
		(pad "2" smd circle
			(at -0.40005 0 180)
			(size 0 0)
			(layers "B.Cu" "B.Mask" "B.Paste")
			(net "GND")
		)
	)
	(footprint ""
		(layer "B.Cu")
		(at 146.80057 -385.50088 -90)
		(property "Reference" "C386"
			(at 0 0 90)
			(layer "B.SilkS")
			(hide yes)
			(effects
				(font
					(size 1.27 1.27)
				)
				(justify mirror)
			)
		)
		(property "Value" ""
			(at 0 0 90)
			(layer "B.Fab")
			(effects
				(font
					(size 1.27 1.27)
				)
				(justify mirror)
			)
		)
		(duplicate_pad_numbers_are_jumpers no)
		(fp_line
			(start -0.299974 0.150114)
			(end 0.299974 0.150114)
			(stroke
				(width 0.1)
				(type default)
			)
			(layer "B.Fab")
		)
		(fp_line
			(start 0.299974 0.150114)
			(end 0.299974 -0.150114)
			(stroke
				(width 0.1)
				(type default)
			)
			(layer "B.Fab")
		)
		(fp_line
			(start -0.299974 -0.150114)
			(end -0.299974 0.150114)
			(stroke
				(width 0.1)
				(type default)
			)
			(layer "B.Fab")
		)
		(fp_line
			(start 0.299974 -0.150114)
			(end -0.299974 -0.150114)
			(stroke
				(width 0.1)
				(type default)
			)
			(layer "B.Fab")
		)
		(pad "1" smd rect
			(at 0.2667 0 90)
			(size 0.3048 0.381)
			(layers "B.Cu" "B.Mask" "B.Paste")
			(net "P0V9_CPU1_RT2_2A")
		)
		(pad "2" smd rect
			(at -0.2667 0 90)
			(size 0.3048 0.381)
			(layers "B.Cu" "B.Mask" "B.Paste")
			(net "GND")
		)
	)
	(footprint ""
		(layer "B.Cu")
		(at 426.53585 -30.927548)
		(property "Reference" "R6040"
			(at 0 0 0)
			(layer "B.SilkS")
			(hide yes)
			(effects
				(font
					(size 1.27 1.27)
				)
				(justify mirror)
			)
		)
		(property "Value" ""
			(at 0 0 0)
			(layer "B.Fab")
			(effects
				(font
					(size 1.27 1.27)
				)
				(justify mirror)
			)
		)
		(duplicate_pad_numbers_are_jumpers no)
		(fp_line
			(start -0.7874 -0.4064)
			(end -0.7874 0.4064)
			(stroke
				(width 0.1524)
				(type default)
			)
			(layer "B.SilkS")
		)
		(fp_line
			(start -0.7874 0.4064)
			(end 0.7874 0.4064)
			(stroke
				(width 0.1524)
				(type default)
			)
			(layer "B.SilkS")
		)
		(fp_line
			(start 0.7874 -0.4064)
			(end -0.7874 -0.4064)
			(stroke
				(width 0.1524)
				(type default)
			)
			(layer "B.SilkS")
		)
		(fp_line
			(start 0.7874 0.4064)
			(end 0.7874 -0.4064)
			(stroke
				(width 0.1524)
				(type default)
			)
			(layer "B.SilkS")
		)
		(fp_line
			(start -0.67945 -0.3048)
			(end -0.67945 0.3048)
			(stroke
				(width 0.1)
				(type default)
			)
			(layer "B.Fab")
		)
		(fp_line
			(start -0.67945 0.3048)
			(end -0.120396 0.3048)
			(stroke
				(width 0.1)
				(type default)
			)
			(layer "B.Fab")
		)
		(fp_line
			(start -0.12065 -0.3048)
			(end -0.67945 -0.3048)
			(stroke
				(width 0.1)
				(type default)
			)
			(layer "B.Fab")
		)
		(fp_line
			(start -0.12065 -0.2794)
			(end -0.12065 -0.3048)
			(stroke
				(width 0.1)
				(type default)
			)
			(layer "B.Fab")
		)
		(fp_line
			(start -0.120396 0.2794)
			(end 0.12065 0.2794)
			(stroke
				(width 0.1)
				(type default)
			)
			(layer "B.Fab")
		)
		(fp_line
			(start -0.120396 0.3048)
			(end -0.120396 0.2794)
			(stroke
				(width 0.1)
				(type default)
			)
			(layer "B.Fab")
		)
		(fp_line
			(start 0.12065 -0.305054)
			(end 0.12065 -0.2794)
			(stroke
				(width 0.1)
				(type default)
			)
			(layer "B.Fab")
		)
		(fp_line
			(start 0.12065 -0.2794)
			(end -0.12065 -0.2794)
			(stroke
				(width 0.1)
				(type default)
			)
			(layer "B.Fab")
		)
		(fp_line
			(start 0.12065 0.2794)
			(end 0.12065 0.3048)
			(stroke
				(width 0.1)
				(type default)
			)
			(layer "B.Fab")
		)
		(fp_line
			(start 0.12065 0.3048)
			(end 0.67945 0.3048)
			(stroke
				(width 0.1)
				(type default)
			)
			(layer "B.Fab")
		)
		(fp_line
			(start 0.67945 -0.305054)
			(end 0.12065 -0.305054)
			(stroke
				(width 0.1)
				(type default)
			)
			(layer "B.Fab")
		)
		(fp_line
			(start 0.67945 0.3048)
			(end 0.67945 -0.305054)
			(stroke
				(width 0.1)
				(type default)
			)
			(layer "B.Fab")
		)
		(pad "1" smd circle
			(at 0.40005 0 180)
			(size 0 0)
			(layers "B.Cu" "B.Mask" "B.Paste")
			(net "P1V8_AUX")
		)
		(pad "2" smd circle
			(at -0.40005 0 180)
			(size 0 0)
			(layers "B.Cu" "B.Mask" "B.Paste")
			(net "PU_FPGA_DEBUG_LED_CTRL")
		)
	)
	(footprint ""
		(layer "B.Cu")
		(at 123.766834 -245.868952 -90)
		(property "Reference" "C2336"
			(at 0 0 90)
			(layer "B.SilkS")
			(hide yes)
			(effects
				(font
					(size 1.27 1.27)
				)
				(justify mirror)
			)
		)
		(property "Value" ""
			(at 0 0 90)
			(layer "B.Fab")
			(effects
				(font
					(size 1.27 1.27)
				)
				(justify mirror)
			)
		)
		(duplicate_pad_numbers_are_jumpers no)
		(fp_line
			(start -0.7874 0.4064)
			(end 0.7874 0.4064)
			(stroke
				(width 0.1524)
				(type default)
			)
			(layer "B.SilkS")
		)
		(fp_line
			(start 0.7874 0.4064)
			(end 0.7874 -0.4064)
			(stroke
				(width 0.1524)
				(type default)
			)
			(layer "B.SilkS")
		)
		(fp_line
			(start -0.7874 -0.4064)
			(end -0.7874 0.4064)
			(stroke
				(width 0.1524)
				(type default)
			)
			(layer "B.SilkS")
		)
		(fp_line
			(start 0.7874 -0.4064)
			(end -0.7874 -0.4064)
			(stroke
				(width 0.1524)
				(type default)
			)
			(layer "B.SilkS")
		)
		(fp_line
			(start -0.67945 0.3048)
			(end -0.120396 0.3048)
			(stroke
				(width 0.1)
				(type default)
			)
			(layer "B.Fab")
		)
		(fp_line
			(start -0.120396 0.3048)
			(end -0.120396 0.2794)
			(stroke
				(width 0.1)
				(type default)
			)
			(layer "B.Fab")
		)
		(fp_line
			(start 0.12065 0.3048)
			(end 0.67945 0.3048)
			(stroke
				(width 0.1)
				(type default)
			)
			(layer "B.Fab")
		)
		(fp_line
			(start 0.67945 0.3048)
			(end 0.67945 -0.305054)
			(stroke
				(width 0.1)
				(type default)
			)
			(layer "B.Fab")
		)
		(fp_line
			(start -0.120396 0.2794)
			(end 0.12065 0.2794)
			(stroke
				(width 0.1)
				(type default)
			)
			(layer "B.Fab")
		)
		(fp_line
			(start 0.12065 0.2794)
			(end 0.12065 0.3048)
			(stroke
				(width 0.1)
				(type default)
			)
			(layer "B.Fab")
		)
		(fp_line
			(start -0.12065 -0.2794)
			(end -0.12065 -0.3048)
			(stroke
				(width 0.1)
				(type default)
			)
			(layer "B.Fab")
		)
		(fp_line
			(start 0.12065 -0.2794)
			(end -0.12065 -0.2794)
			(stroke
				(width 0.1)
				(type default)
			)
			(layer "B.Fab")
		)
		(fp_line
			(start -0.67945 -0.3048)
			(end -0.67945 0.3048)
			(stroke
				(width 0.1)
				(type default)
			)
			(layer "B.Fab")
		)
		(fp_line
			(start -0.12065 -0.3048)
			(end -0.67945 -0.3048)
			(stroke
				(width 0.1)
				(type default)
			)
			(layer "B.Fab")
		)
		(fp_line
			(start 0.12065 -0.305054)
			(end 0.12065 -0.2794)
			(stroke
				(width 0.1)
				(type default)
			)
			(layer "B.Fab")
		)
		(fp_line
			(start 0.67945 -0.305054)
			(end 0.12065 -0.305054)
			(stroke
				(width 0.1)
				(type default)
			)
			(layer "B.Fab")
		)
		(pad "1" smd circle
			(at 0.40005 0 90)
			(size 0 0)
			(layers "B.Cu" "B.Mask" "B.Paste")
			(net "PVDDCR_CPU0_P1")
		)
		(pad "2" smd circle
			(at -0.40005 0 90)
			(size 0 0)
			(layers "B.Cu" "B.Mask" "B.Paste")
			(net "GND")
		)
	)
	(footprint ""
		(layer "B.Cu")
		(at 402.42617 -202.500484)
		(property "Reference" "U3"
			(at 2.032 -2.377948 0)
			(unlocked yes)
			(layer "B.SilkS")
			(effects
				(font
					(size 0.7874 0.5842)
					(thickness 0.1524)
				)
				(justify left mirror)
			)
		)
		(property "Value" ""
			(at 0 0 0)
			(layer "B.Fab")
			(effects
				(font
					(size 1.27 1.27)
				)
				(justify mirror)
			)
		)
		(duplicate_pad_numbers_are_jumpers no)
		(fp_line
			(start -2.0574 -1.651)
			(end -2.0574 1.651)
			(stroke
				(width 0.1524)
				(type default)
			)
			(layer "B.SilkS")
		)
		(fp_line
			(start -2.0574 1.651)
			(end 2.0574 1.651)
			(stroke
				(width 0.1524)
				(type default)
			)
			(layer "B.SilkS")
		)
		(fp_line
			(start -0.381 -1.651)
			(end -2.0574 -1.651)
			(stroke
				(width 0.1524)
				(type default)
			)
			(layer "B.SilkS")
		)
		(fp_line
			(start 0 -1.016)
			(end -0.381 -1.651)
			(stroke
				(width 0.1524)
				(type default)
			)
			(layer "B.SilkS")
		)
		(fp_line
			(start 0.381 -1.651)
			(end 0 -1.016)
			(stroke
				(width 0.1524)
				(type default)
			)
			(layer "B.SilkS")
		)
		(fp_line
			(start 2.0574 -1.651)
			(end 0.381 -1.651)
			(stroke
				(width 0.1524)
				(type default)
			)
			(layer "B.SilkS")
		)
		(fp_line
			(start 2.0574 1.651)
			(end 2.0574 -1.651)
			(stroke
				(width 0.1524)
				(type default)
			)
			(layer "B.SilkS")
		)
		(fp_poly
			(pts
				(xy 2.159 -1.016) (xy 2.71272 -1.344168) (xy 2.71272 -0.719328)
			)
			(stroke
				(width 0)
				(type default)
			)
			(fill yes)
			(layer "B.SilkS")
		)
		(fp_line
			(start -1.599946 -1.199896)
			(end -1.599946 1.199896)
			(stroke
				(width 0.1)
				(type default)
			)
			(layer "B.Fab")
		)
		(fp_line
			(start -1.599946 1.199896)
			(end -0.899922 1.199896)
			(stroke
				(width 0.1)
				(type default)
			)
			(layer "B.Fab")
		)
		(fp_line
			(start -0.899922 -1.549908)
			(end -0.899922 -1.199896)
			(stroke
				(width 0.1)
				(type default)
			)
			(layer "B.Fab")
		)
		(fp_line
			(start -0.899922 -1.199896)
			(end -1.599946 -1.199896)
			(stroke
				(width 0.1)
				(type default)
			)
			(layer "B.Fab")
		)
		(fp_line
			(start -0.899922 1.199896)
			(end -0.899922 1.549908)
			(stroke
				(width 0.1)
				(type default)
			)
			(layer "B.Fab")
		)
		(fp_line
			(start -0.899922 1.549908)
			(end 0.899922 1.549908)
			(stroke
				(width 0.1)
				(type default)
			)
			(layer "B.Fab")
		)
		(fp_line
			(start 0.899922 -1.549908)
			(end -0.899922 -1.549908)
			(stroke
				(width 0.1)
				(type default)
			)
			(layer "B.Fab")
		)
		(fp_line
			(start 0.899922 -1.199896)
			(end 0.899922 -1.549908)
			(stroke
				(width 0.1)
				(type default)
			)
			(layer "B.Fab")
		)
		(fp_line
			(start 0.899922 1.199896)
			(end 1.599946 1.199896)
			(stroke
				(width 0.1)
				(type default)
			)
			(layer "B.Fab")
		)
		(fp_line
			(start 0.899922 1.549908)
			(end 0.899922 1.199896)
			(stroke
				(width 0.1)
				(type default)
			)
			(layer "B.Fab")
		)
		(fp_line
			(start 1.599946 -1.199896)
			(end 0.899922 -1.199896)
			(stroke
				(width 0.1)
				(type default)
			)
			(layer "B.Fab")
		)
		(fp_line
			(start 1.599946 1.199896)
			(end 1.599946 -1.199896)
			(stroke
				(width 0.1)
				(type default)
			)
			(layer "B.Fab")
		)
		(fp_poly
			(pts
				(xy 2.71272 -0.719328) (xy 2.71272 -1.344168) (xy 2.159 -1.016)
			)
			(stroke
				(width 0)
				(type default)
			)
			(fill yes)
			(layer "B.Fab")
		)
		(pad "1" smd rect
			(at 1.225042 -0.94996 270)
			(size 0.5588 1.3462)
			(layers "B.Cu" "B.Mask" "B.Paste")
			(net "Net_10733")
		)
		(pad "2" smd rect
			(at 1.225042 0 270)
			(size 0.5588 1.3462)
			(layers "B.Cu" "B.Mask" "B.Paste")
			(net "SCM_USB_OC_N")
		)
		(pad "3" smd rect
			(at 1.225042 0.94996 270)
			(size 0.5588 1.3462)
			(layers "B.Cu" "B.Mask" "B.Paste")
			(net "GND")
		)
		(pad "4" smd rect
			(at -1.225042 0.94996 270)
			(size 0.5588 1.3462)
			(layers "B.Cu" "B.Mask" "B.Paste")
			(net "SCM_USB_OC_BU_R_N")
		)
		(pad "5" smd rect
			(at -1.225042 -0.94996 270)
			(size 0.5588 1.3462)
			(layers "B.Cu" "B.Mask" "B.Paste")
			(net "P1V8_AUX")
		)
	)
)
